# T6G (Grand Teton) — schematic netlist excerpt (pin names and nets, part order shuffled) for the footprints in the layout excerpt that follows; sources: Cadence DE-HDL packaged netlist, KiCad conversion of 04192023_DAF0TMB3IC0_F0TG_MB_C_brd_V02_OCP.brd

U211  74LVC2G07DW7  74LVC2G07DW-7 IC  pkg SOT363_0-65_2X1-25XC  page 134
  \1a\  = OCP_SFF_PRSNT0_R_N
  GND  = GND
  \2a\  = OCP_SFF_PRSNT1_R_N
  \2y\  = HP_LVC3_OCP_V3_1_PRSNT2_N_R
  VCC  = P3V3_AUX
  \1y\  = HP_LVC3_OCP_V3_1_PRSNT2_N_R

PR6533  Q_RES  22.1K 1% CHIP  pkg 0402LF  page 364 : A = GND ; B = P0V9_RETIMER_CPU1_ADDR

(kicad_pcb
	(version 20260206)
	(generator "pcbnew")
	(generator_version "10.0")
	(general
		(thickness 1.6)
		(legacy_teardrops no)
	)
	(paper "A4")
	(title_block
		(title "04192023_DAF0TMB3IC0_F0TG_MB_C_brd_V02_OCP.brd")
		(comment 1 "Grand Teton / footprints 3274-3275 of 8354")
	)
	(layers
		(0 "F.Cu" signal "TOP")
		(4 "In1.Cu" signal "GND")
		(6 "In2.Cu" signal "IN1")
		(8 "In3.Cu" signal "GND1")
		(10 "In4.Cu" signal "IN2")
		(12 "In5.Cu" signal "GND2")
		(14 "In6.Cu" signal "IN3")
		(16 "In7.Cu" signal "GND3")
		(18 "In8.Cu" signal "VCC")
		(20 "In9.Cu" signal "VCC1")
		(22 "In10.Cu" signal "GND4")
		(24 "In11.Cu" signal "IN4")
		(26 "In12.Cu" signal "GND5")
		(28 "In13.Cu" signal "IN5")
		(30 "In14.Cu" signal "GND6")
		(32 "In15.Cu" signal "IN6")
		(34 "In16.Cu" signal "GND7")
		(2 "B.Cu" signal "BOTTOM")
		(9 "F.Adhes" user "F.Adhesive")
		(11 "B.Adhes" user "B.Adhesive")
		(13 "F.Paste" user "Package Geometry/Pastemask Top")
		(15 "B.Paste" user "Package Geometry/Pastemask Bottom")
		(5 "F.SilkS" user "Ref Des/Silkscreen Top")
		(7 "B.SilkS" user "Ref Des/Silkscreen Bottom")
		(1 "F.Mask" user "Board Geometry/Soldermask Top")
		(3 "B.Mask" user "Board Geometry/Soldermask Bottom")
		(17 "Dwgs.User" user "User.Drawings")
		(19 "Cmts.User" user "User.Comments")
		(21 "Eco1.User" user "User.Eco1")
		(23 "Eco2.User" user "User.Eco2")
		(25 "Edge.Cuts" user "Board Geometry/Outline")
		(27 "Margin" user)
		(31 "F.CrtYd" user "Package Geometry/Place Bound Top")
		(29 "B.CrtYd" user "Package Geometry/Place Bound Bottom")
		(35 "F.Fab" user "Ref Des/Assembly Top")
		(33 "B.Fab" user "Ref Des/Assembly Bottom")
	)
	(footprint ""
		(layer "F.Cu")
		(at 457.684632 -107.018836)
		(property "Reference" "U211"
			(at -1.4732 -1.768348 0)
			(unlocked yes)
			(layer "F.SilkS")
			(effects
				(font
					(size 0.7874 0.5842)
					(thickness 0.1524)
				)
				(justify left)
			)
		)
		(property "Value" ""
			(at 0 0 0)
			(layer "F.Fab")
			(effects
				(font
					(size 1.27 1.27)
				)
			)
		)
		(duplicate_pad_numbers_are_jumpers no)
		(fp_line
			(start -1.38176 -1.100074)
			(end -1.38176 1.100074)
			(stroke
				(width 0.1524)
				(type default)
			)
			(layer "F.SilkS")
		)
		(fp_line
			(start -1.38176 1.100074)
			(end 1.38176 1.100074)
			(stroke
				(width 0.1524)
				(type default)
			)
			(layer "F.SilkS")
		)
		(fp_line
			(start -0.592074 -1.100074)
			(end -1.38176 -1.100074)
			(stroke
				(width 0.1524)
				(type default)
			)
			(layer "F.SilkS")
		)
		(fp_line
			(start 0 -0.508)
			(end -0.592074 -1.100074)
			(stroke
				(width 0.1524)
				(type default)
			)
			(layer "F.SilkS")
		)
		(fp_line
			(start 0.592074 -1.100074)
			(end 0 -0.508)
			(stroke
				(width 0.1524)
				(type default)
			)
			(layer "F.SilkS")
		)
		(fp_line
			(start 1.38176 -1.100074)
			(end 0.592074 -1.100074)
			(stroke
				(width 0.1524)
				(type default)
			)
			(layer "F.SilkS")
		)
		(fp_line
			(start 1.38176 1.100074)
			(end 1.38176 -1.100074)
			(stroke
				(width 0.1524)
				(type default)
			)
			(layer "F.SilkS")
		)
		(fp_poly
			(pts
				(xy -1.9431 -0.429768) (xy -1.9431 -0.870204) (xy -1.50241 -0.649986)
			)
			(stroke
				(width 0)
				(type default)
			)
			(fill yes)
			(layer "F.SilkS")
		)
		(fp_line
			(start -0.674878 -1.100074)
			(end -0.674878 1.100074)
			(stroke
				(width 0.1)
				(type default)
			)
			(layer "F.Fab")
		)
		(fp_line
			(start -0.674878 1.100074)
			(end 0.674878 1.100074)
			(stroke
				(width 0.1)
				(type default)
			)
			(layer "F.Fab")
		)
		(fp_line
			(start 0.674878 -1.100074)
			(end -0.674878 -1.100074)
			(stroke
				(width 0.1)
				(type default)
			)
			(layer "F.Fab")
		)
		(fp_line
			(start 0.674878 1.100074)
			(end 0.674878 -1.100074)
			(stroke
				(width 0.1)
				(type default)
			)
			(layer "F.Fab")
		)
		(fp_poly
			(pts
				(xy -1.9431 -0.870204) (xy -1.50241 -0.649986) (xy -1.9431 -0.429768)
			)
			(stroke
				(width 0)
				(type default)
			)
			(fill yes)
			(layer "F.Fab")
		)
		(pad "1" smd rect
			(at -0.94996 -0.649986 270)
			(size 0.4318 0.6096)
			(layers "F.Cu" "F.Mask" "F.Paste")
			(net "OCP_SFF_PRSNT0_R_N")
		)
		(pad "2" smd rect
			(at -0.94996 0 270)
			(size 0.4318 0.6096)
			(layers "F.Cu" "F.Mask" "F.Paste")
			(net "GND")
		)
		(pad "3" smd rect
			(at -0.94996 0.649986 270)
			(size 0.4318 0.6096)
			(layers "F.Cu" "F.Mask" "F.Paste")
			(net "OCP_SFF_PRSNT1_R_N")
		)
		(pad "4" smd rect
			(at 0.94996 0.649986 270)
			(size 0.4318 0.6096)
			(layers "F.Cu" "F.Mask" "F.Paste")
			(net "HP_LVC3_OCP_V3_1_PRSNT2_N_R")
		)
		(pad "5" smd rect
			(at 0.94996 0 270)
			(size 0.4318 0.6096)
			(layers "F.Cu" "F.Mask" "F.Paste")
			(net "P3V3_AUX")
		)
		(pad "6" smd rect
			(at 0.94996 -0.649986 270)
			(size 0.4318 0.6096)
			(layers "F.Cu" "F.Mask" "F.Paste")
			(net "HP_LVC3_OCP_V3_1_PRSNT2_N_R")
		)
	)
	(footprint ""
		(layer "F.Cu")
		(at 10.066782 -412.215584)
		(property "Reference" "PR6533"
			(at 0 0 0)
			(layer "F.SilkS")
			(hide yes)
			(effects
				(font
					(size 1.27 1.27)
				)
			)
		)
		(property "Value" ""
			(at 0 0 0)
			(layer "F.Fab")
			(effects
				(font
					(size 1.27 1.27)
				)
			)
		)
		(duplicate_pad_numbers_are_jumpers no)
		(fp_line
			(start -0.7874 -0.4064)
			(end 0.7874 -0.4064)
			(stroke
				(width 0.1524)
				(type default)
			)
			(layer "F.SilkS")
		)
		(fp_line
			(start -0.7874 0.4064)
			(end -0.7874 -0.4064)
			(stroke
				(width 0.1524)
				(type default)
			)
			(layer "F.SilkS")
		)
		(fp_line
			(start 0.7874 -0.4064)
			(end 0.7874 0.4064)
			(stroke
				(width 0.1524)
				(type default)
			)
			(layer "F.SilkS")
		)
		(fp_line
			(start 0.7874 0.4064)
			(end -0.7874 0.4064)
			(stroke
				(width 0.1524)
				(type default)
			)
			(layer "F.SilkS")
		)
		(fp_line
			(start -0.67945 -0.305054)
			(end -0.12065 -0.305054)
			(stroke
				(width 0.1)
				(type default)
			)
			(layer "F.Fab")
		)
		(fp_line
			(start -0.67945 0.3048)
			(end -0.67945 -0.305054)
			(stroke
				(width 0.1)
				(type default)
			)
			(layer "F.Fab")
		)
		(fp_line
			(start -0.12065 -0.305054)
			(end -0.12065 -0.2794)
			(stroke
				(width 0.1)
				(type default)
			)
			(layer "F.Fab")
		)
		(fp_line
			(start -0.12065 -0.2794)
			(end 0.12065 -0.2794)
			(stroke
				(width 0.1)
				(type default)
			)
			(layer "F.Fab")
		)
		(fp_line
			(start -0.12065 0.2794)
			(end -0.12065 0.3048)
			(stroke
				(width 0.1)
				(type default)
			)
			(layer "F.Fab")
		)
		(fp_line
			(start -0.12065 0.3048)
			(end -0.67945 0.3048)
			(stroke
				(width 0.1)
				(type default)
			)
			(layer "F.Fab")
		)
		(fp_line
			(start 0.120396 0.2794)
			(end -0.12065 0.2794)
			(stroke
				(width 0.1)
				(type default)
			)
			(layer "F.Fab")
		)
		(fp_line
			(start 0.120396 0.3048)
			(end 0.120396 0.2794)
			(stroke
				(width 0.1)
				(type default)
			)
			(layer "F.Fab")
		)
		(fp_line
			(start 0.12065 -0.3048)
			(end 0.67945 -0.3048)
			(stroke
				(width 0.1)
				(type default)
			)
			(layer "F.Fab")
		)
		(fp_line
			(start 0.12065 -0.2794)
			(end 0.12065 -0.3048)
			(stroke
				(width 0.1)
				(type default)
			)
			(layer "F.Fab")
		)
		(fp_line
			(start 0.67945 -0.3048)
			(end 0.67945 0.3048)
			(stroke
				(width 0.1)
				(type default)
			)
			(layer "F.Fab")
		)
		(fp_line
			(start 0.67945 0.3048)
			(end 0.120396 0.3048)
			(stroke
				(width 0.1)
				(type default)
			)
			(layer "F.Fab")
		)
		(pad "1" smd circle
			(at -0.40005 0)
			(size 0 0)
			(layers "F.Cu" "F.Mask" "F.Paste")
			(net "GND")
		)
		(pad "2" smd circle
			(at 0.40005 0)
			(size 0 0)
			(layers "F.Cu" "F.Mask" "F.Paste")
			(net "P0V9_RETIMER_CPU1_ADDR")
		)
	)
)
